(kicad_pcb
	(version 20260206)
	(generator "pcbnew")
	(generator_version "10.0")
	(general
		(thickness 1.6)
		(legacy_teardrops no)
	)
	(paper "A4")
	(title_block
		(title "v1-chassis-manager — T6M_CM_d_v01_1031_1645.brd")
		(comment 1 "Open CloudServer (Microsoft) / footprints 1533-1541 of 2512")
	)
	(layers
		(0 "F.Cu" signal "TOP")
		(4 "In1.Cu" signal "GND1")
		(6 "In2.Cu" signal "IN1")
		(8 "In3.Cu" signal "VCC1")
		(10 "In4.Cu" signal "VCC2")
		(12 "In5.Cu" signal "GND2")
		(14 "In6.Cu" signal "IN2")
		(16 "In7.Cu" signal "IN3")
		(18 "In8.Cu" signal "GND3")
		(2 "B.Cu" signal "BOTTOM")
		(9 "F.Adhes" user "F.Adhesive")
		(11 "B.Adhes" user "B.Adhesive")
		(13 "F.Paste" user "Package Geometry/Pastemask Top")
		(15 "B.Paste" user "Package Geometry/Pastemask Bottom")
		(5 "F.SilkS" user "Ref Des/Silkscreen Top")
		(7 "B.SilkS" user "Ref Des/Silkscreen Bottom")
		(1 "F.Mask" user "Board Geometry/Soldermask Top")
		(3 "B.Mask" user "Board Geometry/Soldermask Bottom")
		(17 "Dwgs.User" user "User.Drawings")
		(19 "Cmts.User" user "User.Comments")
		(21 "Eco1.User" user "User.Eco1")
		(23 "Eco2.User" user "User.Eco2")
		(25 "Edge.Cuts" user "Board Geometry/Outline")
		(27 "Margin" user)
		(31 "F.CrtYd" user "Package Geometry/Place Bound Top")
		(29 "B.CrtYd" user "Package Geometry/Place Bound Bottom")
		(35 "F.Fab" user "Ref Des/Assembly Top")
		(33 "B.Fab" user "Ref Des/Assembly Bottom")
	)
	(footprint ""
		(layer "F.Cu")
		(at 128.77927 -110.92815)
		(property "Reference" "C13"
			(at -5.883656 -0.032512 0)
			(unlocked yes)
			(layer "F.SilkS")
			(effects
				(font
					(size 0.7874 0.5842)
					(thickness 0.1524)
				)
				(justify left)
			)
		)
		(property "Value" ""
			(at 0 0 0)
			(layer "F.Fab")
			(effects
				(font
					(size 1.27 1.27)
				)
			)
		)
		(duplicate_pad_numbers_are_jumpers no)
		(fp_line
			(start -0.7874 -0.4064)
			(end 0.7874 -0.4064)
			(stroke
				(width 0.1524)
				(type default)
			)
			(layer "F.SilkS")
		)
		(fp_line
			(start -0.7874 0.4064)
			(end -0.7874 -0.4064)
			(stroke
				(width 0.1524)
				(type default)
			)
			(layer "F.SilkS")
		)
		(fp_line
			(start 0 0.381)
			(end 0 -0.381)
			(stroke
				(width 0.1524)
				(type default)
			)
			(layer "F.SilkS")
		)
		(fp_line
			(start 0.7874 -0.4064)
			(end 0.7874 0.4064)
			(stroke
				(width 0.1524)
				(type default)
			)
			(layer "F.SilkS")
		)
		(fp_line
			(start 0.7874 0.4064)
			(end -0.7874 0.4064)
			(stroke
				(width 0.1524)
				(type default)
			)
			(layer "F.SilkS")
		)
		(fp_poly
			(pts
				(xy -0.5334 0.254) (xy -0.635 0.254) (xy -0.635 0.2286) (xy -0.635 -0.254) (xy -0.5334 -0.254) (xy -0.5334 -0.2794)
				(xy 0.5334 -0.2794) (xy 0.5334 -0.254) (xy 0.635 -0.254) (xy 0.635 0.254) (xy 0.5334 0.254) (xy 0.5334 0.2794)
				(xy -0.508 0.2794) (xy -0.5334 0.2794)
			)
			(stroke
				(width 0)
				(type default)
			)
			(fill no)
			(layer "F.CrtYd")
		)
		(pad "1" smd rect
			(at 0.40005 0)
			(size 0.4572 0.508)
			(layers "F.Cu" "F.Mask" "F.Paste")
			(net "XTAL_CLK_NODE1_X2")
		)
		(pad "2" smd rect
			(at -0.40005 0)
			(size 0.4572 0.508)
			(layers "F.Cu" "F.Mask" "F.Paste")
			(net "GND")
		)
	)
	(footprint ""
		(layer "F.Cu")
		(at 115.478052 -42.45356 -90)
		(property "Reference" "OSC4"
			(at 4.26339 0.976884 0)
			(unlocked yes)
			(layer "F.SilkS")
			(effects
				(font
					(size 0.7874 0.5842)
					(thickness 0.1524)
				)
				(justify left)
			)
		)
		(property "Value" ""
			(at 0 0 270)
			(layer "F.Fab")
			(effects
				(font
					(size 1.27 1.27)
				)
			)
		)
		(duplicate_pad_numbers_are_jumpers no)
		(fp_line
			(start -3.599942 2.599944)
			(end -3.599942 -2.599944)
			(stroke
				(width 0.1524)
				(type default)
			)
			(layer "F.SilkS")
		)
		(fp_line
			(start 3.599942 2.599944)
			(end -3.599942 2.599944)
			(stroke
				(width 0.1524)
				(type default)
			)
			(layer "F.SilkS")
		)
		(fp_line
			(start -3.599942 -2.599944)
			(end 3.599942 -2.599944)
			(stroke
				(width 0.1524)
				(type default)
			)
			(layer "F.SilkS")
		)
		(fp_line
			(start 3.599942 -2.599944)
			(end 3.599942 2.599944)
			(stroke
				(width 0.1524)
				(type default)
			)
			(layer "F.SilkS")
		)
		(fp_poly
			(pts
				(xy -2.54 2.667) (xy -3.302 4.191) (xy -1.778 4.191)
			)
			(stroke
				(width 0)
				(type default)
			)
			(fill yes)
			(layer "F.SilkS")
		)
		(fp_rect
			(start -3.599942 2.599944)
			(end 3.599942 -2.599944)
			(stroke
				(width 0)
				(type default)
			)
			(fill no)
			(layer "F.CrtYd")
		)
		(fp_line
			(start -3.599942 2.599944)
			(end -3.599942 -2.599944)
			(stroke
				(width 0.1)
				(type default)
			)
			(layer "F.Fab")
		)
		(fp_line
			(start 3.599942 2.599944)
			(end -3.599942 2.599944)
			(stroke
				(width 0.1)
				(type default)
			)
			(layer "F.Fab")
		)
		(fp_line
			(start -3.599942 -2.599944)
			(end 3.599942 -2.599944)
			(stroke
				(width 0.1)
				(type default)
			)
			(layer "F.Fab")
		)
		(fp_line
			(start 3.599942 -2.599944)
			(end 3.599942 2.599944)
			(stroke
				(width 0.1)
				(type default)
			)
			(layer "F.Fab")
		)
		(fp_poly
			(pts
				(xy -2.54 2.667) (xy -3.302 4.191) (xy -1.778 4.191)
			)
			(stroke
				(width 0)
				(type default)
			)
			(fill yes)
			(layer "F.Fab")
		)
		(fp_text user "2"
			(at 2.692146 3.206496 0)
			(unlocked yes)
			(layer "F.SilkS")
			(effects
				(font
					(size 0.635 0.4064)
					(thickness 0.1524)
				)
				(justify left)
			)
		)
		(fp_text user "1"
			(at -1.845056 3.151378 0)
			(unlocked yes)
			(layer "F.SilkS")
			(effects
				(font
					(size 0.635 0.4064)
					(thickness 0.1524)
				)
				(justify left)
			)
		)
		(fp_text user "3"
			(at -0.430276 -2.766568 0)
			(unlocked yes)
			(layer "F.SilkS")
			(effects
				(font
					(size 0.635 0.4064)
					(thickness 0.1524)
				)
				(justify left)
			)
		)
		(fp_text user "4"
			(at -2.545334 -2.769108 0)
			(unlocked yes)
			(layer "F.SilkS")
			(effects
				(font
					(size 0.7874 0.5842)
					(thickness 0.1524)
				)
				(justify left)
			)
		)
		(fp_text user "1"
			(at -3.5941 3.337052 270)
			(unlocked yes)
			(layer "F.Fab")
			(effects
				(font
					(size 0.7874 0.5842)
					(thickness 0.000001)
				)
				(justify left)
			)
		)
		(fp_text user "2"
			(at 2.2479 3.337052 270)
			(unlocked yes)
			(layer "F.Fab")
			(effects
				(font
					(size 0.7874 0.5842)
					(thickness 0.000001)
				)
				(justify left)
			)
		)
		(fp_text user "4"
			(at -2.8321 -3.139948 270)
			(unlocked yes)
			(layer "F.Fab")
			(effects
				(font
					(size 0.7874 0.5842)
					(thickness 0.000001)
				)
				(justify left)
			)
		)
		(fp_text user "3"
			(at 2.2479 -3.139948 270)
			(unlocked yes)
			(layer "F.Fab")
			(effects
				(font
					(size 0.7874 0.5842)
					(thickness 0.000001)
				)
				(justify left)
			)
		)
		(pad "1" smd rect
			(at -2.54 1.849882)
			(size 1.1176 1.4224)
			(layers "F.Cu" "F.Mask" "F.Paste")
			(net "N21550241")
		)
		(pad "2" smd rect
			(at 2.54 1.849882)
			(size 1.1176 1.4224)
			(layers "F.Cu" "F.Mask" "F.Paste")
			(net "GND")
		)
		(pad "3" smd rect
			(at 2.54 -1.849882)
			(size 1.1176 1.4224)
			(layers "F.Cu" "F.Mask" "F.Paste")
			(net "OSC1_48MHZ")
		)
		(pad "4" smd rect
			(at -2.54 -1.849882)
			(size 1.1176 1.4224)
			(layers "F.Cu" "F.Mask" "F.Paste")
			(net "N46114787")
		)
	)
	(footprint ""
		(layer "F.Cu")
		(at 111.21771 -140.547598)
		(property "Reference" "PR60"
			(at 2.96545 -4.32435 0)
			(unlocked yes)
			(layer "F.SilkS")
			(effects
				(font
					(size 0.635 0.4064)
					(thickness 0.1524)
				)
				(justify left)
			)
		)
		(property "Value" ""
			(at 0 0 0)
			(layer "F.Fab")
			(effects
				(font
					(size 1.27 1.27)
				)
			)
		)
		(duplicate_pad_numbers_are_jumpers no)
		(fp_line
			(start -0.7874 -0.4064)
			(end 0.7874 -0.4064)
			(stroke
				(width 0.1524)
				(type default)
			)
			(layer "F.SilkS")
		)
		(fp_line
			(start -0.7874 0.4064)
			(end -0.7874 -0.4064)
			(stroke
				(width 0.1524)
				(type default)
			)
			(layer "F.SilkS")
		)
		(fp_line
			(start 0.7874 -0.4064)
			(end 0.7874 0.4064)
			(stroke
				(width 0.1524)
				(type default)
			)
			(layer "F.SilkS")
		)
		(fp_line
			(start 0.7874 0.4064)
			(end -0.7874 0.4064)
			(stroke
				(width 0.1524)
				(type default)
			)
			(layer "F.SilkS")
		)
		(fp_poly
			(pts
				(xy -0.508 0.2794) (xy -0.508 0.2286) (xy -0.635 0.2286) (xy -0.635 -0.254) (xy -0.5334 -0.254)
				(xy -0.5334 -0.2794) (xy 0.5334 -0.2794) (xy 0.5334 -0.254) (xy 0.635 -0.254) (xy 0.635 0.254) (xy 0.5334 0.254)
				(xy 0.5334 0.2794)
			)
			(stroke
				(width 0)
				(type default)
			)
			(fill no)
			(layer "F.CrtYd")
		)
		(pad "1" smd rect
			(at 0.40005 0)
			(size 0.4572 0.508)
			(layers "F.Cu" "F.Mask" "F.Paste")
			(net "AGND_PVCCP_NODE1")
		)
		(pad "2" smd rect
			(at -0.40005 0)
			(size 0.4572 0.508)
			(layers "F.Cu" "F.Mask" "F.Paste")
			(net "VR_PVCCP_NODE1_SETINI")
		)
	)
	(footprint ""
		(layer "F.Cu")
		(at 99.455986 -154.3177 -90)
		(property "Reference" "PC36"
			(at -0.964692 -0.001016 90)
			(unlocked yes)
			(layer "F.SilkS")
			(effects
				(font
					(size 0.7874 0.5842)
					(thickness 0.1524)
				)
				(justify left)
			)
		)
		(property "Value" ""
			(at 0 0 270)
			(layer "F.Fab")
			(effects
				(font
					(size 1.27 1.27)
				)
			)
		)
		(duplicate_pad_numbers_are_jumpers no)
		(fp_line
			(start -0.7874 0.4064)
			(end -0.7874 -0.4064)
			(stroke
				(width 0.1524)
				(type default)
			)
			(layer "F.SilkS")
		)
		(fp_line
			(start 0.7874 0.4064)
			(end -0.7874 0.4064)
			(stroke
				(width 0.1524)
				(type default)
			)
			(layer "F.SilkS")
		)
		(fp_line
			(start 0 0.381)
			(end 0 -0.381)
			(stroke
				(width 0.1524)
				(type default)
			)
			(layer "F.SilkS")
		)
		(fp_line
			(start -0.7874 -0.4064)
			(end 0.7874 -0.4064)
			(stroke
				(width 0.1524)
				(type default)
			)
			(layer "F.SilkS")
		)
		(fp_line
			(start 0.7874 -0.4064)
			(end 0.7874 0.4064)
			(stroke
				(width 0.1524)
				(type default)
			)
			(layer "F.SilkS")
		)
		(fp_poly
			(pts
				(xy -0.5334 0.254) (xy -0.635 0.254) (xy -0.635 0.2286) (xy -0.635 -0.254) (xy -0.5334 -0.254) (xy -0.5334 -0.2794)
				(xy 0.5334 -0.2794) (xy 0.5334 -0.254) (xy 0.635 -0.254) (xy 0.635 0.254) (xy 0.5334 0.254) (xy 0.5334 0.2794)
				(xy -0.508 0.2794) (xy -0.5334 0.2794)
			)
			(stroke
				(width 0)
				(type default)
			)
			(fill no)
			(layer "F.CrtYd")
		)
		(pad "1" smd rect
			(at 0.40005 0 270)
			(size 0.4572 0.508)
			(layers "F.Cu" "F.Mask" "F.Paste")
			(net "SW_P1V8_STB_NODE1_BT")
		)
		(pad "2" smd rect
			(at -0.40005 0 270)
			(size 0.4572 0.508)
			(layers "F.Cu" "F.Mask" "F.Paste")
			(net "SW_P1V8_STB_NODE1_PH")
		)
	)
	(footprint ""
		(layer "F.Cu")
		(at 64.24676 -188.126624 -90)
		(property "Reference" "R931"
			(at -4.548886 0.146558 90)
			(unlocked yes)
			(layer "F.SilkS")
			(effects
				(font
					(size 0.7874 0.5842)
					(thickness 0.1524)
				)
				(justify left)
			)
		)
		(property "Value" ""
			(at 0 0 270)
			(layer "F.Fab")
			(effects
				(font
					(size 1.27 1.27)
				)
			)
		)
		(duplicate_pad_numbers_are_jumpers no)
		(fp_line
			(start -0.7874 0.406146)
			(end -0.7874 -0.406146)
			(stroke
				(width 0.1524)
				(type default)
			)
			(layer "F.SilkS")
		)
		(fp_line
			(start 0.7874 0.406146)
			(end -0.7874 0.406146)
			(stroke
				(width 0.1524)
				(type default)
			)
			(layer "F.SilkS")
		)
		(fp_line
			(start -0.7874 -0.406146)
			(end 0.7874 -0.406146)
			(stroke
				(width 0.1524)
				(type default)
			)
			(layer "F.SilkS")
		)
		(fp_line
			(start 0.7874 -0.406146)
			(end 0.7874 0.406146)
			(stroke
				(width 0.1524)
				(type default)
			)
			(layer "F.SilkS")
		)
		(fp_poly
			(pts
				(xy -0.508 0.2794) (xy -0.508 0.2286) (xy -0.635 0.2286) (xy -0.635 -0.254) (xy -0.5334 -0.254)
				(xy -0.5334 -0.2794) (xy 0.5334 -0.2794) (xy 0.5334 -0.254) (xy 0.635 -0.254) (xy 0.635 0.254) (xy 0.5334 0.254)
				(xy 0.5334 0.2794)
			)
			(stroke
				(width 0)
				(type default)
			)
			(fill no)
			(layer "F.CrtYd")
		)
		(pad "1" smd rect
			(at 0.40005 0 270)
			(size 0.4572 0.508)
			(layers "F.Cu" "F.Mask" "F.Paste")
			(net "UART_T2_NODE1_RXD")
		)
		(pad "2" smd rect
			(at -0.40005 0 270)
			(size 0.4572 0.508)
			(layers "F.Cu" "F.Mask" "F.Paste")
			(net "UART_T2_NODE1_RXD_R")
		)
	)
	(footprint ""
		(layer "F.Cu")
		(at 43.498516 -4.177538 90)
		(property "Reference" "PC75"
			(at -3.59791 -13.713968 90)
			(unlocked yes)
			(layer "F.SilkS")
			(effects
				(font
					(size 0.7874 0.5842)
					(thickness 0.1524)
				)
				(justify left)
			)
		)
		(property "Value" ""
			(at 0 0 90)
			(layer "F.Fab")
			(effects
				(font
					(size 1.27 1.27)
				)
			)
		)
		(duplicate_pad_numbers_are_jumpers no)
		(fp_line
			(start 0.7874 -0.4064)
			(end 0.7874 0.4064)
			(stroke
				(width 0.1524)
				(type default)
			)
			(layer "F.SilkS")
		)
		(fp_line
			(start -0.7874 -0.4064)
			(end 0.7874 -0.4064)
			(stroke
				(width 0.1524)
				(type default)
			)
			(layer "F.SilkS")
		)
		(fp_line
			(start 0 0.381)
			(end 0 -0.381)
			(stroke
				(width 0.1524)
				(type default)
			)
			(layer "F.SilkS")
		)
		(fp_line
			(start 0.7874 0.4064)
			(end -0.7874 0.4064)
			(stroke
				(width 0.1524)
				(type default)
			)
			(layer "F.SilkS")
		)
		(fp_line
			(start -0.7874 0.4064)
			(end -0.7874 -0.4064)
			(stroke
				(width 0.1524)
				(type default)
			)
			(layer "F.SilkS")
		)
		(fp_poly
			(pts
				(xy -0.5334 0.254) (xy -0.635 0.254) (xy -0.635 0.2286) (xy -0.635 -0.254) (xy -0.5334 -0.254) (xy -0.5334 -0.2794)
				(xy 0.5334 -0.2794) (xy 0.5334 -0.254) (xy 0.635 -0.254) (xy 0.635 0.254) (xy 0.5334 0.254) (xy 0.5334 0.2794)
				(xy -0.508 0.2794) (xy -0.5334 0.2794)
			)
			(stroke
				(width 0)
				(type default)
			)
			(fill no)
			(layer "F.CrtYd")
		)
		(pad "1" smd rect
			(at 0.40005 0 90)
			(size 0.4572 0.508)
			(layers "F.Cu" "F.Mask" "F.Paste")
			(net "SW_PV_VDDR_NODE1_VIN_FLT")
		)
		(pad "2" smd rect
			(at -0.40005 0 90)
			(size 0.4572 0.508)
			(layers "F.Cu" "F.Mask" "F.Paste")
			(net "GND")
		)
	)
	(footprint ""
		(layer "F.Cu")
		(at 114.473228 -18.60931 90)
		(property "Reference" "C198"
			(at -1.661668 5.643118 90)
			(unlocked yes)
			(layer "F.SilkS")
			(effects
				(font
					(size 0.7874 0.5842)
					(thickness 0.1524)
				)
				(justify left)
			)
		)
		(property "Value" ""
			(at 0 0 90)
			(layer "F.Fab")
			(effects
				(font
					(size 1.27 1.27)
				)
			)
		)
		(duplicate_pad_numbers_are_jumpers no)
		(fp_line
			(start 0.7874 -0.4064)
			(end 0.7874 0.4064)
			(stroke
				(width 0.1524)
				(type default)
			)
			(layer "F.SilkS")
		)
		(fp_line
			(start -0.7874 -0.4064)
			(end 0.7874 -0.4064)
			(stroke
				(width 0.1524)
				(type default)
			)
			(layer "F.SilkS")
		)
		(fp_line
			(start 0 0.381)
			(end 0 -0.381)
			(stroke
				(width 0.1524)
				(type default)
			)
			(layer "F.SilkS")
		)
		(fp_line
			(start 0.7874 0.4064)
			(end -0.7874 0.4064)
			(stroke
				(width 0.1524)
				(type default)
			)
			(layer "F.SilkS")
		)
		(fp_line
			(start -0.7874 0.4064)
			(end -0.7874 -0.4064)
			(stroke
				(width 0.1524)
				(type default)
			)
			(layer "F.SilkS")
		)
		(fp_poly
			(pts
				(xy -0.5334 0.254) (xy -0.635 0.254) (xy -0.635 0.2286) (xy -0.635 -0.254) (xy -0.5334 -0.254) (xy -0.5334 -0.2794)
				(xy 0.5334 -0.2794) (xy 0.5334 -0.254) (xy 0.635 -0.254) (xy 0.635 0.254) (xy 0.5334 0.254) (xy 0.5334 0.2794)
				(xy -0.508 0.2794) (xy -0.5334 0.2794)
			)
			(stroke
				(width 0)
				(type default)
			)
			(fill no)
			(layer "F.CrtYd")
		)
		(pad "1" smd rect
			(at 0.40005 0 90)
			(size 0.4572 0.508)
			(layers "F.Cu" "F.Mask" "F.Paste")
			(net "FM_CPLD_NODE1_PVTT_DDR_EN")
		)
		(pad "2" smd rect
			(at -0.40005 0 90)
			(size 0.4572 0.508)
			(layers "F.Cu" "F.Mask" "F.Paste")
			(net "GND")
		)
	)
	(footprint ""
		(layer "F.Cu")
		(at 13.039598 -133.21919 -90)
		(property "Reference" "PR29"
			(at 0.50546 2.120138 90)
			(unlocked yes)
			(layer "F.SilkS")
			(effects
				(font
					(size 0.7874 0.5842)
					(thickness 0.1524)
				)
				(justify left)
			)
		)
		(property "Value" ""
			(at 0 0 270)
			(layer "F.Fab")
			(effects
				(font
					(size 1.27 1.27)
				)
			)
		)
		(duplicate_pad_numbers_are_jumpers no)
		(fp_line
			(start -0.7874 0.4064)
			(end -0.7874 -0.4064)
			(stroke
				(width 0.1524)
				(type default)
			)
			(layer "F.SilkS")
		)
		(fp_line
			(start 0.7874 0.4064)
			(end -0.7874 0.4064)
			(stroke
				(width 0.1524)
				(type default)
			)
			(layer "F.SilkS")
		)
		(fp_line
			(start -0.7874 -0.4064)
			(end 0.7874 -0.4064)
			(stroke
				(width 0.1524)
				(type default)
			)
			(layer "F.SilkS")
		)
		(fp_line
			(start 0.7874 -0.4064)
			(end 0.7874 0.4064)
			(stroke
				(width 0.1524)
				(type default)
			)
			(layer "F.SilkS")
		)
		(fp_poly
			(pts
				(xy -0.508 0.2794) (xy -0.508 0.2286) (xy -0.635 0.2286) (xy -0.635 -0.254) (xy -0.5334 -0.254)
				(xy -0.5334 -0.2794) (xy 0.5334 -0.2794) (xy 0.5334 -0.254) (xy 0.635 -0.254) (xy 0.635 0.254) (xy 0.5334 0.254)
				(xy 0.5334 0.2794)
			)
			(stroke
				(width 0)
				(type default)
			)
			(fill no)
			(layer "F.CrtYd")
		)
		(pad "1" smd rect
			(at 0.40005 0 270)
			(size 0.4572 0.508)
			(layers "F.Cu" "F.Mask" "F.Paste")
			(net "VSENSE_P1V05_NODE1_P")
		)
		(pad "2" smd rect
			(at -0.40005 0 270)
			(size 0.4572 0.508)
			(layers "F.Cu" "F.Mask" "F.Paste")
			(net "P1V05_NODE1_VSNS")
		)
	)
	(footprint ""
		(layer "F.Cu")
		(at 98.373946 -4.449826)
		(property "Reference" "C334"
			(at -0.563626 1.177544 0)
			(unlocked yes)
			(layer "F.SilkS")
			(effects
				(font
					(size 0.7874 0.5842)
					(thickness 0.1524)
				)
				(justify left)
			)
		)
		(property "Value" ""
			(at 0 0 0)
			(layer "F.Fab")
			(effects
				(font
					(size 1.27 1.27)
				)
			)
		)
		(duplicate_pad_numbers_are_jumpers no)
		(fp_line
			(start -0.7874 -0.4064)
			(end 0.7874 -0.4064)
			(stroke
				(width 0.1524)
				(type default)
			)
			(layer "F.SilkS")
		)
		(fp_line
			(start -0.7874 0.4064)
			(end -0.7874 -0.4064)
			(stroke
				(width 0.1524)
				(type default)
			)
			(layer "F.SilkS")
		)
		(fp_line
			(start 0 0.381)
			(end 0 -0.381)
			(stroke
				(width 0.1524)
				(type default)
			)
			(layer "F.SilkS")
		)
		(fp_line
			(start 0.7874 -0.4064)
			(end 0.7874 0.4064)
			(stroke
				(width 0.1524)
				(type default)
			)
			(layer "F.SilkS")
		)
		(fp_line
			(start 0.7874 0.4064)
			(end -0.7874 0.4064)
			(stroke
				(width 0.1524)
				(type default)
			)
			(layer "F.SilkS")
		)
		(fp_poly
			(pts
				(xy -0.5334 0.254) (xy -0.635 0.254) (xy -0.635 0.2286) (xy -0.635 -0.254) (xy -0.5334 -0.254) (xy -0.5334 -0.2794)
				(xy 0.5334 -0.2794) (xy 0.5334 -0.254) (xy 0.635 -0.254) (xy 0.635 0.254) (xy 0.5334 0.254) (xy 0.5334 0.2794)
				(xy -0.508 0.2794) (xy -0.5334 0.2794)
			)
			(stroke
				(width 0)
				(type default)
			)
			(fill no)
			(layer "F.CrtYd")
		)
		(pad "1" smd rect
			(at 0.40005 0)
			(size 0.4572 0.508)
			(layers "F.Cu" "F.Mask" "F.Paste")
			(net "P3V3_NODE1")
		)
		(pad "2" smd rect
			(at -0.40005 0)
			(size 0.4572 0.508)
			(layers "F.Cu" "F.Mask" "F.Paste")
			(net "GND")
		)
	)
)
